# T6G (Grand Teton) — schematic netlist excerpt (pin names and nets, part order shuffled) for the footprints in the layout excerpt that follows; sources: Cadence DE-HDL packaged netlist, KiCad conversion of 04192023_DAF0TMB3IC0_F0TG_MB_C_brd_V02_OCP.brd

R1675  Q_RES  10 1% CHIP  pkg 0402LF  page 87 : A = I3C_SPD_DDRAF_CPU0_SDA ; B = I3C_SPD_DDRB_CPU0_SDA
C181  Q_CAP  10UF 25V 10% X6S  pkg C0805  page 101 : A = P12V_MEM_CPU1 ; B = GND
R3487  Q_RES  10K 1% CHIP  pkg 0402LF  page 126 : A = P3V3_AUX ; B = GPU_PRSNT_N

(kicad_pcb
	(version 20260206)
	(generator "pcbnew")
	(generator_version "10.0")
	(general
		(thickness 1.6)
		(legacy_teardrops no)
	)
	(paper "A4")
	(title_block
		(title "04192023_DAF0TMB3IC0_F0TG_MB_C_brd_V02_OCP.brd")
		(comment 1 "Grand Teton / footprints 5491-5493 of 8354")
	)
	(layers
		(0 "F.Cu" signal "TOP")
		(4 "In1.Cu" signal "GND")
		(6 "In2.Cu" signal "IN1")
		(8 "In3.Cu" signal "GND1")
		(10 "In4.Cu" signal "IN2")
		(12 "In5.Cu" signal "GND2")
		(14 "In6.Cu" signal "IN3")
		(16 "In7.Cu" signal "GND3")
		(18 "In8.Cu" signal "VCC")
		(20 "In9.Cu" signal "VCC1")
		(22 "In10.Cu" signal "GND4")
		(24 "In11.Cu" signal "IN4")
		(26 "In12.Cu" signal "GND5")
		(28 "In13.Cu" signal "IN5")
		(30 "In14.Cu" signal "GND6")
		(32 "In15.Cu" signal "IN6")
		(34 "In16.Cu" signal "GND7")
		(2 "B.Cu" signal "BOTTOM")
		(9 "F.Adhes" user "F.Adhesive")
		(11 "B.Adhes" user "B.Adhesive")
		(13 "F.Paste" user "Package Geometry/Pastemask Top")
		(15 "B.Paste" user "Package Geometry/Pastemask Bottom")
		(5 "F.SilkS" user "Ref Des/Silkscreen Top")
		(7 "B.SilkS" user "Ref Des/Silkscreen Bottom")
		(1 "F.Mask" user "Board Geometry/Soldermask Top")
		(3 "B.Mask" user "Board Geometry/Soldermask Bottom")
		(17 "Dwgs.User" user "User.Drawings")
		(19 "Cmts.User" user "User.Comments")
		(21 "Eco1.User" user "User.Eco1")
		(23 "Eco2.User" user "User.Eco2")
		(25 "Edge.Cuts" user "Board Geometry/Outline")
		(27 "Margin" user)
		(31 "F.CrtYd" user "Package Geometry/Place Bound Top")
		(29 "B.CrtYd" user "Package Geometry/Place Bound Bottom")
		(35 "F.Fab" user "Ref Des/Assembly Top")
		(33 "B.Fab" user "Ref Des/Assembly Bottom")
	)
	(footprint ""
		(layer "B.Cu")
		(at 52.782978 -429.84293 90)
		(property "Reference" "R3487"
			(at 0 0 90)
			(layer "B.SilkS")
			(hide yes)
			(effects
				(font
					(size 1.27 1.27)
				)
				(justify mirror)
			)
		)
		(property "Value" ""
			(at 0 0 90)
			(layer "B.Fab")
			(effects
				(font
					(size 1.27 1.27)
				)
				(justify mirror)
			)
		)
		(duplicate_pad_numbers_are_jumpers no)
		(fp_line
			(start 0.7874 -0.4064)
			(end -0.7874 -0.4064)
			(stroke
				(width 0.1524)
				(type default)
			)
			(layer "B.SilkS")
		)
		(fp_line
			(start -0.7874 -0.4064)
			(end -0.7874 0.4064)
			(stroke
				(width 0.1524)
				(type default)
			)
			(layer "B.SilkS")
		)
		(fp_line
			(start 0.7874 0.4064)
			(end 0.7874 -0.4064)
			(stroke
				(width 0.1524)
				(type default)
			)
			(layer "B.SilkS")
		)
		(fp_line
			(start -0.7874 0.4064)
			(end 0.7874 0.4064)
			(stroke
				(width 0.1524)
				(type default)
			)
			(layer "B.SilkS")
		)
		(fp_line
			(start 0.67945 -0.305054)
			(end 0.12065 -0.305054)
			(stroke
				(width 0.1)
				(type default)
			)
			(layer "B.Fab")
		)
		(fp_line
			(start 0.12065 -0.305054)
			(end 0.12065 -0.2794)
			(stroke
				(width 0.1)
				(type default)
			)
			(layer "B.Fab")
		)
		(fp_line
			(start -0.12065 -0.3048)
			(end -0.67945 -0.3048)
			(stroke
				(width 0.1)
				(type default)
			)
			(layer "B.Fab")
		)
		(fp_line
			(start -0.67945 -0.3048)
			(end -0.67945 0.3048)
			(stroke
				(width 0.1)
				(type default)
			)
			(layer "B.Fab")
		)
		(fp_line
			(start 0.12065 -0.2794)
			(end -0.12065 -0.2794)
			(stroke
				(width 0.1)
				(type default)
			)
			(layer "B.Fab")
		)
		(fp_line
			(start -0.12065 -0.2794)
			(end -0.12065 -0.3048)
			(stroke
				(width 0.1)
				(type default)
			)
			(layer "B.Fab")
		)
		(fp_line
			(start 0.12065 0.2794)
			(end 0.12065 0.3048)
			(stroke
				(width 0.1)
				(type default)
			)
			(layer "B.Fab")
		)
		(fp_line
			(start -0.120396 0.2794)
			(end 0.12065 0.2794)
			(stroke
				(width 0.1)
				(type default)
			)
			(layer "B.Fab")
		)
		(fp_line
			(start 0.67945 0.3048)
			(end 0.67945 -0.305054)
			(stroke
				(width 0.1)
				(type default)
			)
			(layer "B.Fab")
		)
		(fp_line
			(start 0.12065 0.3048)
			(end 0.67945 0.3048)
			(stroke
				(width 0.1)
				(type default)
			)
			(layer "B.Fab")
		)
		(fp_line
			(start -0.120396 0.3048)
			(end -0.120396 0.2794)
			(stroke
				(width 0.1)
				(type default)
			)
			(layer "B.Fab")
		)
		(fp_line
			(start -0.67945 0.3048)
			(end -0.120396 0.3048)
			(stroke
				(width 0.1)
				(type default)
			)
			(layer "B.Fab")
		)
		(pad "1" smd circle
			(at 0.40005 0 270)
			(size 0 0)
			(layers "B.Cu" "B.Mask" "B.Paste")
			(net "P3V3_AUX")
		)
		(pad "2" smd circle
			(at -0.40005 0 270)
			(size 0 0)
			(layers "B.Cu" "B.Mask" "B.Paste")
			(net "GPU_PRSNT_N")
		)
	)
	(footprint ""
		(layer "B.Cu")
		(at 36.796218 -192.66027)
		(property "Reference" "C181"
			(at 0 0 0)
			(layer "B.SilkS")
			(hide yes)
			(effects
				(font
					(size 1.27 1.27)
				)
				(justify mirror)
			)
		)
		(property "Value" ""
			(at 0 0 0)
			(layer "B.Fab")
			(effects
				(font
					(size 1.27 1.27)
				)
				(justify mirror)
			)
		)
		(duplicate_pad_numbers_are_jumpers no)
		(fp_line
			(start -1.524 -0.762)
			(end -1.524 0.762)
			(stroke
				(width 0.1524)
				(type default)
			)
			(layer "B.SilkS")
		)
		(fp_line
			(start -1.524 0.762)
			(end 1.524 0.762)
			(stroke
				(width 0.1524)
				(type default)
			)
			(layer "B.SilkS")
		)
		(fp_line
			(start 1.524 -0.762)
			(end -1.524 -0.762)
			(stroke
				(width 0.1524)
				(type default)
			)
			(layer "B.SilkS")
		)
		(fp_line
			(start 1.524 0.762)
			(end 1.524 -0.762)
			(stroke
				(width 0.1524)
				(type default)
			)
			(layer "B.SilkS")
		)
		(fp_line
			(start -1.1049 -0.724916)
			(end 1.1049 -0.724916)
			(stroke
				(width 0.1)
				(type default)
			)
			(layer "B.Fab")
		)
		(fp_line
			(start -1.1049 0.724916)
			(end -1.1049 -0.724916)
			(stroke
				(width 0.1)
				(type default)
			)
			(layer "B.Fab")
		)
		(fp_line
			(start 1.1049 -0.724916)
			(end 1.1049 0.724916)
			(stroke
				(width 0.1)
				(type default)
			)
			(layer "B.Fab")
		)
		(fp_line
			(start 1.1049 0.724916)
			(end -1.1049 0.724916)
			(stroke
				(width 0.1)
				(type default)
			)
			(layer "B.Fab")
		)
		(pad "1" smd rect
			(at 0.889 0)
			(size 1.016 1.27)
			(layers "B.Cu" "B.Mask" "B.Paste")
			(net "P12V_MEM_CPU1")
		)
		(pad "2" smd rect
			(at -0.889 0)
			(size 1.016 1.27)
			(layers "B.Cu" "B.Mask" "B.Paste")
			(net "GND")
		)
	)
	(footprint ""
		(layer "B.Cu")
		(at 299.06849 -195.859146 180)
		(property "Reference" "R1675"
			(at 0 0 0)
			(layer "B.SilkS")
			(hide yes)
			(effects
				(font
					(size 1.27 1.27)
				)
				(justify mirror)
			)
		)
		(property "Value" ""
			(at 0 0 0)
			(layer "B.Fab")
			(effects
				(font
					(size 1.27 1.27)
				)
				(justify mirror)
			)
		)
		(duplicate_pad_numbers_are_jumpers no)
		(fp_line
			(start 0.7874 0.4064)
			(end 0.7874 -0.4064)
			(stroke
				(width 0.1524)
				(type default)
			)
			(layer "B.SilkS")
		)
		(fp_line
			(start 0.7874 -0.4064)
			(end -0.7874 -0.4064)
			(stroke
				(width 0.1524)
				(type default)
			)
			(layer "B.SilkS")
		)
		(fp_line
			(start -0.7874 0.4064)
			(end 0.7874 0.4064)
			(stroke
				(width 0.1524)
				(type default)
			)
			(layer "B.SilkS")
		)
		(fp_line
			(start -0.7874 -0.4064)
			(end -0.7874 0.4064)
			(stroke
				(width 0.1524)
				(type default)
			)
			(layer "B.SilkS")
		)
		(fp_line
			(start 0.67945 0.3048)
			(end 0.67945 -0.305054)
			(stroke
				(width 0.1)
				(type default)
			)
			(layer "B.Fab")
		)
		(fp_line
			(start 0.67945 -0.305054)
			(end 0.12065 -0.305054)
			(stroke
				(width 0.1)
				(type default)
			)
			(layer "B.Fab")
		)
		(fp_line
			(start 0.12065 0.3048)
			(end 0.67945 0.3048)
			(stroke
				(width 0.1)
				(type default)
			)
			(layer "B.Fab")
		)
		(fp_line
			(start 0.12065 0.2794)
			(end 0.12065 0.3048)
			(stroke
				(width 0.1)
				(type default)
			)
			(layer "B.Fab")
		)
		(fp_line
			(start 0.12065 -0.2794)
			(end -0.12065 -0.2794)
			(stroke
				(width 0.1)
				(type default)
			)
			(layer "B.Fab")
		)
		(fp_line
			(start 0.12065 -0.305054)
			(end 0.12065 -0.2794)
			(stroke
				(width 0.1)
				(type default)
			)
			(layer "B.Fab")
		)
		(fp_line
			(start -0.120396 0.3048)
			(end -0.120396 0.2794)
			(stroke
				(width 0.1)
				(type default)
			)
			(layer "B.Fab")
		)
		(fp_line
			(start -0.120396 0.2794)
			(end 0.12065 0.2794)
			(stroke
				(width 0.1)
				(type default)
			)
			(layer "B.Fab")
		)
		(fp_line
			(start -0.12065 -0.2794)
			(end -0.12065 -0.3048)
			(stroke
				(width 0.1)
				(type default)
			)
			(layer "B.Fab")
		)
		(fp_line
			(start -0.12065 -0.3048)
			(end -0.67945 -0.3048)
			(stroke
				(width 0.1)
				(type default)
			)
			(layer "B.Fab")
		)
		(fp_line
			(start -0.67945 0.3048)
			(end -0.120396 0.3048)
			(stroke
				(width 0.1)
				(type default)
			)
			(layer "B.Fab")
		)
		(fp_line
			(start -0.67945 -0.3048)
			(end -0.67945 0.3048)
			(stroke
				(width 0.1)
				(type default)
			)
			(layer "B.Fab")
		)
		(pad "1" smd circle
			(at 0.40005 0)
			(size 0 0)
			(layers "B.Cu" "B.Mask" "B.Paste")
			(net "I3C_SPD_DDRAF_CPU0_SDA")
		)
		(pad "2" smd circle
			(at -0.40005 0)
			(size 0 0)
			(layers "B.Cu" "B.Mask" "B.Paste")
			(net "I3C_SPD_DDRB_CPU0_SDA")
		)
	)
)
